(kicad_pcb
	(version 20260206)
	(generator "pcbnew")
	(generator_version "10.0")
	(general
		(thickness 1.6)
		(legacy_teardrops no)
	)
	(paper "A4")
	(title_block
		(title "04192023_DAF0TMB3IC0_F0TG_MB_C_brd_V02_OCP.brd")
		(comment 1 "Grand Teton / footprints 3956-3962 of 8354")
	)
	(layers
		(0 "F.Cu" signal "TOP")
		(4 "In1.Cu" signal "GND")
		(6 "In2.Cu" signal "IN1")
		(8 "In3.Cu" signal "GND1")
		(10 "In4.Cu" signal "IN2")
		(12 "In5.Cu" signal "GND2")
		(14 "In6.Cu" signal "IN3")
		(16 "In7.Cu" signal "GND3")
		(18 "In8.Cu" signal "VCC")
		(20 "In9.Cu" signal "VCC1")
		(22 "In10.Cu" signal "GND4")
		(24 "In11.Cu" signal "IN4")
		(26 "In12.Cu" signal "GND5")
		(28 "In13.Cu" signal "IN5")
		(30 "In14.Cu" signal "GND6")
		(32 "In15.Cu" signal "IN6")
		(34 "In16.Cu" signal "GND7")
		(2 "B.Cu" signal "BOTTOM")
		(9 "F.Adhes" user "F.Adhesive")
		(11 "B.Adhes" user "B.Adhesive")
		(13 "F.Paste" user "Package Geometry/Pastemask Top")
		(15 "B.Paste" user "Package Geometry/Pastemask Bottom")
		(5 "F.SilkS" user "Ref Des/Silkscreen Top")
		(7 "B.SilkS" user "Ref Des/Silkscreen Bottom")
		(1 "F.Mask" user "Board Geometry/Soldermask Top")
		(3 "B.Mask" user "Board Geometry/Soldermask Bottom")
		(17 "Dwgs.User" user "User.Drawings")
		(19 "Cmts.User" user "User.Comments")
		(21 "Eco1.User" user "User.Eco1")
		(23 "Eco2.User" user "User.Eco2")
		(25 "Edge.Cuts" user "Board Geometry/Outline")
		(27 "Margin" user)
		(31 "F.CrtYd" user "Package Geometry/Place Bound Top")
		(29 "B.CrtYd" user "Package Geometry/Place Bound Bottom")
		(35 "F.Fab" user "Ref Des/Assembly Top")
		(33 "B.Fab" user "Ref Des/Assembly Bottom")
	)
	(footprint ""
		(layer "F.Cu")
		(at 277.650956 -428.556166 180)
		(property "Reference" "R4266"
			(at 0 0 180)
			(layer "F.SilkS")
			(hide yes)
			(effects
				(font
					(size 1.27 1.27)
				)
			)
		)
		(property "Value" ""
			(at 0 0 180)
			(layer "F.Fab")
			(effects
				(font
					(size 1.27 1.27)
				)
			)
		)
		(duplicate_pad_numbers_are_jumpers no)
		(fp_line
			(start 0.7874 0.4064)
			(end -0.7874 0.4064)
			(stroke
				(width 0.1524)
				(type default)
			)
			(layer "F.SilkS")
		)
		(fp_line
			(start 0.7874 -0.4064)
			(end 0.7874 0.4064)
			(stroke
				(width 0.1524)
				(type default)
			)
			(layer "F.SilkS")
		)
		(fp_line
			(start -0.7874 0.4064)
			(end -0.7874 -0.4064)
			(stroke
				(width 0.1524)
				(type default)
			)
			(layer "F.SilkS")
		)
		(fp_line
			(start -0.7874 -0.4064)
			(end 0.7874 -0.4064)
			(stroke
				(width 0.1524)
				(type default)
			)
			(layer "F.SilkS")
		)
		(fp_line
			(start 0.67945 0.3048)
			(end 0.120396 0.3048)
			(stroke
				(width 0.1)
				(type default)
			)
			(layer "F.Fab")
		)
		(fp_line
			(start 0.67945 -0.3048)
			(end 0.67945 0.3048)
			(stroke
				(width 0.1)
				(type default)
			)
			(layer "F.Fab")
		)
		(fp_line
			(start 0.12065 -0.2794)
			(end 0.12065 -0.3048)
			(stroke
				(width 0.1)
				(type default)
			)
			(layer "F.Fab")
		)
		(fp_line
			(start 0.12065 -0.3048)
			(end 0.67945 -0.3048)
			(stroke
				(width 0.1)
				(type default)
			)
			(layer "F.Fab")
		)
		(fp_line
			(start 0.120396 0.3048)
			(end 0.120396 0.2794)
			(stroke
				(width 0.1)
				(type default)
			)
			(layer "F.Fab")
		)
		(fp_line
			(start 0.120396 0.2794)
			(end -0.12065 0.2794)
			(stroke
				(width 0.1)
				(type default)
			)
			(layer "F.Fab")
		)
		(fp_line
			(start -0.12065 0.3048)
			(end -0.67945 0.3048)
			(stroke
				(width 0.1)
				(type default)
			)
			(layer "F.Fab")
		)
		(fp_line
			(start -0.12065 0.2794)
			(end -0.12065 0.3048)
			(stroke
				(width 0.1)
				(type default)
			)
			(layer "F.Fab")
		)
		(fp_line
			(start -0.12065 -0.2794)
			(end 0.12065 -0.2794)
			(stroke
				(width 0.1)
				(type default)
			)
			(layer "F.Fab")
		)
		(fp_line
			(start -0.12065 -0.305054)
			(end -0.12065 -0.2794)
			(stroke
				(width 0.1)
				(type default)
			)
			(layer "F.Fab")
		)
		(fp_line
			(start -0.67945 0.3048)
			(end -0.67945 -0.305054)
			(stroke
				(width 0.1)
				(type default)
			)
			(layer "F.Fab")
		)
		(fp_line
			(start -0.67945 -0.305054)
			(end -0.12065 -0.305054)
			(stroke
				(width 0.1)
				(type default)
			)
			(layer "F.Fab")
		)
		(pad "1" smd circle
			(at -0.40005 0 180)
			(size 0 0)
			(layers "F.Cu" "F.Mask" "F.Paste")
			(net "PWRGD_P3V3_AUX_PDB_BUF_R")
		)
		(pad "2" smd circle
			(at 0.40005 0 180)
			(size 0 0)
			(layers "F.Cu" "F.Mask" "F.Paste")
			(net "PWRGD_P3V3_AUX_PDB_BUF")
		)
	)
	(footprint ""
		(layer "F.Cu")
		(at 177.81016 -394.1318)
		(property "Reference" "R1499"
			(at 0 0 0)
			(layer "F.SilkS")
			(hide yes)
			(effects
				(font
					(size 1.27 1.27)
				)
			)
		)
		(property "Value" ""
			(at 0 0 0)
			(layer "F.Fab")
			(effects
				(font
					(size 1.27 1.27)
				)
			)
		)
		(duplicate_pad_numbers_are_jumpers no)
		(fp_line
			(start -0.32512 -0.175006)
			(end 0.32512 -0.175006)
			(stroke
				(width 0.1)
				(type default)
			)
			(layer "F.Fab")
		)
		(fp_line
			(start -0.32512 0.175006)
			(end -0.32512 -0.175006)
			(stroke
				(width 0.1)
				(type default)
			)
			(layer "F.Fab")
		)
		(fp_line
			(start 0.32512 -0.175006)
			(end 0.32512 0.175006)
			(stroke
				(width 0.1)
				(type default)
			)
			(layer "F.Fab")
		)
		(fp_line
			(start 0.32512 0.175006)
			(end -0.32512 0.175006)
			(stroke
				(width 0.1)
				(type default)
			)
			(layer "F.Fab")
		)
		(pad "1" smd rect
			(at -0.2667 0)
			(size 0.3048 0.381)
			(layers "F.Cu" "F.Mask" "F.Paste")
			(net "P1V8_CPU1_RT_1D")
		)
		(pad "2" smd rect
			(at 0.2667 0 180)
			(size 0.3048 0.381)
			(layers "F.Cu" "F.Mask" "F.Paste")
			(net "JTAG_TCK_RT_CPU1_P2")
		)
	)
	(footprint ""
		(layer "F.Cu")
		(at 438.558432 -27.275536 -90)
		(property "Reference" "PR3842"
			(at 0 0 270)
			(layer "F.SilkS")
			(hide yes)
			(effects
				(font
					(size 1.27 1.27)
				)
			)
		)
		(property "Value" ""
			(at 0 0 270)
			(layer "F.Fab")
			(effects
				(font
					(size 1.27 1.27)
				)
			)
		)
		(duplicate_pad_numbers_are_jumpers no)
		(fp_line
			(start -0.7874 0.4064)
			(end -0.7874 -0.4064)
			(stroke
				(width 0.1524)
				(type default)
			)
			(layer "F.SilkS")
		)
		(fp_line
			(start 0.7874 0.4064)
			(end -0.7874 0.4064)
			(stroke
				(width 0.1524)
				(type default)
			)
			(layer "F.SilkS")
		)
		(fp_line
			(start -0.7874 -0.4064)
			(end 0.7874 -0.4064)
			(stroke
				(width 0.1524)
				(type default)
			)
			(layer "F.SilkS")
		)
		(fp_line
			(start 0.7874 -0.4064)
			(end 0.7874 0.4064)
			(stroke
				(width 0.1524)
				(type default)
			)
			(layer "F.SilkS")
		)
		(fp_line
			(start -0.67945 0.3048)
			(end -0.67945 -0.305054)
			(stroke
				(width 0.1)
				(type default)
			)
			(layer "F.Fab")
		)
		(fp_line
			(start -0.12065 0.3048)
			(end -0.67945 0.3048)
			(stroke
				(width 0.1)
				(type default)
			)
			(layer "F.Fab")
		)
		(fp_line
			(start 0.120396 0.3048)
			(end 0.120396 0.2794)
			(stroke
				(width 0.1)
				(type default)
			)
			(layer "F.Fab")
		)
		(fp_line
			(start 0.67945 0.3048)
			(end 0.120396 0.3048)
			(stroke
				(width 0.1)
				(type default)
			)
			(layer "F.Fab")
		)
		(fp_line
			(start -0.12065 0.2794)
			(end -0.12065 0.3048)
			(stroke
				(width 0.1)
				(type default)
			)
			(layer "F.Fab")
		)
		(fp_line
			(start 0.120396 0.2794)
			(end -0.12065 0.2794)
			(stroke
				(width 0.1)
				(type default)
			)
			(layer "F.Fab")
		)
		(fp_line
			(start -0.12065 -0.2794)
			(end 0.12065 -0.2794)
			(stroke
				(width 0.1)
				(type default)
			)
			(layer "F.Fab")
		)
		(fp_line
			(start 0.12065 -0.2794)
			(end 0.12065 -0.3048)
			(stroke
				(width 0.1)
				(type default)
			)
			(layer "F.Fab")
		)
		(fp_line
			(start 0.12065 -0.3048)
			(end 0.67945 -0.3048)
			(stroke
				(width 0.1)
				(type default)
			)
			(layer "F.Fab")
		)
		(fp_line
			(start 0.67945 -0.3048)
			(end 0.67945 0.3048)
			(stroke
				(width 0.1)
				(type default)
			)
			(layer "F.Fab")
		)
		(fp_line
			(start -0.67945 -0.305054)
			(end -0.12065 -0.305054)
			(stroke
				(width 0.1)
				(type default)
			)
			(layer "F.Fab")
		)
		(fp_line
			(start -0.12065 -0.305054)
			(end -0.12065 -0.2794)
			(stroke
				(width 0.1)
				(type default)
			)
			(layer "F.Fab")
		)
		(pad "1" smd circle
			(at -0.40005 0 270)
			(size 0 0)
			(layers "F.Cu" "F.Mask" "F.Paste")
			(net "P12V_OCP_OV_FB_1")
		)
		(pad "2" smd circle
			(at 0.40005 0 270)
			(size 0 0)
			(layers "F.Cu" "F.Mask" "F.Paste")
			(net "GND")
		)
	)
	(footprint ""
		(layer "F.Cu")
		(at 127.381 -108.712 90)
		(property "Reference" "C8017"
			(at 0 0 90)
			(layer "F.SilkS")
			(hide yes)
			(effects
				(font
					(size 1.27 1.27)
				)
			)
		)
		(property "Value" ""
			(at 0 0 90)
			(layer "F.Fab")
			(effects
				(font
					(size 1.27 1.27)
				)
			)
		)
		(duplicate_pad_numbers_are_jumpers no)
		(fp_line
			(start 0.7874 -0.4064)
			(end 0.7874 0.4064)
			(stroke
				(width 0.1524)
				(type default)
			)
			(layer "F.SilkS")
		)
		(fp_line
			(start -0.7874 -0.4064)
			(end 0.7874 -0.4064)
			(stroke
				(width 0.1524)
				(type default)
			)
			(layer "F.SilkS")
		)
		(fp_line
			(start 0.7874 0.4064)
			(end -0.7874 0.4064)
			(stroke
				(width 0.1524)
				(type default)
			)
			(layer "F.SilkS")
		)
		(fp_line
			(start -0.7874 0.4064)
			(end -0.7874 -0.4064)
			(stroke
				(width 0.1524)
				(type default)
			)
			(layer "F.SilkS")
		)
		(fp_line
			(start -0.12065 -0.305054)
			(end -0.12065 -0.2794)
			(stroke
				(width 0.1)
				(type default)
			)
			(layer "F.Fab")
		)
		(fp_line
			(start -0.67945 -0.305054)
			(end -0.12065 -0.305054)
			(stroke
				(width 0.1)
				(type default)
			)
			(layer "F.Fab")
		)
		(fp_line
			(start 0.67945 -0.3048)
			(end 0.67945 0.3048)
			(stroke
				(width 0.1)
				(type default)
			)
			(layer "F.Fab")
		)
		(fp_line
			(start 0.12065 -0.3048)
			(end 0.67945 -0.3048)
			(stroke
				(width 0.1)
				(type default)
			)
			(layer "F.Fab")
		)
		(fp_line
			(start 0.12065 -0.2794)
			(end 0.12065 -0.3048)
			(stroke
				(width 0.1)
				(type default)
			)
			(layer "F.Fab")
		)
		(fp_line
			(start -0.12065 -0.2794)
			(end 0.12065 -0.2794)
			(stroke
				(width 0.1)
				(type default)
			)
			(layer "F.Fab")
		)
		(fp_line
			(start 0.120396 0.2794)
			(end -0.12065 0.2794)
			(stroke
				(width 0.1)
				(type default)
			)
			(layer "F.Fab")
		)
		(fp_line
			(start -0.12065 0.2794)
			(end -0.12065 0.3048)
			(stroke
				(width 0.1)
				(type default)
			)
			(layer "F.Fab")
		)
		(fp_line
			(start 0.67945 0.3048)
			(end 0.120396 0.3048)
			(stroke
				(width 0.1)
				(type default)
			)
			(layer "F.Fab")
		)
		(fp_line
			(start 0.120396 0.3048)
			(end 0.120396 0.2794)
			(stroke
				(width 0.1)
				(type default)
			)
			(layer "F.Fab")
		)
		(fp_line
			(start -0.12065 0.3048)
			(end -0.67945 0.3048)
			(stroke
				(width 0.1)
				(type default)
			)
			(layer "F.Fab")
		)
		(fp_line
			(start -0.67945 0.3048)
			(end -0.67945 -0.305054)
			(stroke
				(width 0.1)
				(type default)
			)
			(layer "F.Fab")
		)
		(pad "1" smd circle
			(at -0.40005 0 90)
			(size 0 0)
			(layers "F.Cu" "F.Mask" "F.Paste")
			(net "UV_ADR_P2V5_COMP")
		)
		(pad "2" smd circle
			(at 0.40005 0 90)
			(size 0 0)
			(layers "F.Cu" "F.Mask" "F.Paste")
			(net "GND")
		)
	)
	(footprint ""
		(layer "F.Cu")
		(at 185.806842 -24.170132)
		(property "Reference" "PC2234"
			(at 0 0 0)
			(layer "F.SilkS")
			(hide yes)
			(effects
				(font
					(size 1.27 1.27)
				)
			)
		)
		(property "Value" ""
			(at 0 0 0)
			(layer "F.Fab")
			(effects
				(font
					(size 1.27 1.27)
				)
			)
		)
		(duplicate_pad_numbers_are_jumpers no)
		(fp_line
			(start -0.7874 -0.4064)
			(end 0.7874 -0.4064)
			(stroke
				(width 0.1524)
				(type default)
			)
			(layer "F.SilkS")
		)
		(fp_line
			(start -0.7874 0.4064)
			(end -0.7874 -0.4064)
			(stroke
				(width 0.1524)
				(type default)
			)
			(layer "F.SilkS")
		)
		(fp_line
			(start 0.7874 -0.4064)
			(end 0.7874 0.4064)
			(stroke
				(width 0.1524)
				(type default)
			)
			(layer "F.SilkS")
		)
		(fp_line
			(start 0.7874 0.4064)
			(end -0.7874 0.4064)
			(stroke
				(width 0.1524)
				(type default)
			)
			(layer "F.SilkS")
		)
		(fp_line
			(start -0.67945 -0.305054)
			(end -0.12065 -0.305054)
			(stroke
				(width 0.1)
				(type default)
			)
			(layer "F.Fab")
		)
		(fp_line
			(start -0.67945 0.3048)
			(end -0.67945 -0.305054)
			(stroke
				(width 0.1)
				(type default)
			)
			(layer "F.Fab")
		)
		(fp_line
			(start -0.12065 -0.305054)
			(end -0.12065 -0.2794)
			(stroke
				(width 0.1)
				(type default)
			)
			(layer "F.Fab")
		)
		(fp_line
			(start -0.12065 -0.2794)
			(end 0.12065 -0.2794)
			(stroke
				(width 0.1)
				(type default)
			)
			(layer "F.Fab")
		)
		(fp_line
			(start -0.12065 0.2794)
			(end -0.12065 0.3048)
			(stroke
				(width 0.1)
				(type default)
			)
			(layer "F.Fab")
		)
		(fp_line
			(start -0.12065 0.3048)
			(end -0.67945 0.3048)
			(stroke
				(width 0.1)
				(type default)
			)
			(layer "F.Fab")
		)
		(fp_line
			(start 0.120396 0.2794)
			(end -0.12065 0.2794)
			(stroke
				(width 0.1)
				(type default)
			)
			(layer "F.Fab")
		)
		(fp_line
			(start 0.120396 0.3048)
			(end 0.120396 0.2794)
			(stroke
				(width 0.1)
				(type default)
			)
			(layer "F.Fab")
		)
		(fp_line
			(start 0.12065 -0.3048)
			(end 0.67945 -0.3048)
			(stroke
				(width 0.1)
				(type default)
			)
			(layer "F.Fab")
		)
		(fp_line
			(start 0.12065 -0.2794)
			(end 0.12065 -0.3048)
			(stroke
				(width 0.1)
				(type default)
			)
			(layer "F.Fab")
		)
		(fp_line
			(start 0.67945 -0.3048)
			(end 0.67945 0.3048)
			(stroke
				(width 0.1)
				(type default)
			)
			(layer "F.Fab")
		)
		(fp_line
			(start 0.67945 0.3048)
			(end 0.120396 0.3048)
			(stroke
				(width 0.1)
				(type default)
			)
			(layer "F.Fab")
		)
		(pad "1" smd circle
			(at -0.40005 0)
			(size 0 0)
			(layers "F.Cu" "F.Mask" "F.Paste")
			(net "GND")
		)
		(pad "2" smd circle
			(at 0.40005 0)
			(size 0 0)
			(layers "F.Cu" "F.Mask" "F.Paste")
			(net "P12V_SCM_REG")
		)
	)
	(footprint ""
		(layer "F.Cu")
		(at 200.952608 -114.641376)
		(property "Reference" "R4172"
			(at 0 0 0)
			(layer "F.SilkS")
			(hide yes)
			(effects
				(font
					(size 1.27 1.27)
				)
			)
		)
		(property "Value" ""
			(at 0 0 0)
			(layer "F.Fab")
			(effects
				(font
					(size 1.27 1.27)
				)
			)
		)
		(duplicate_pad_numbers_are_jumpers no)
		(fp_line
			(start -0.7874 -0.4064)
			(end 0.7874 -0.4064)
			(stroke
				(width 0.1524)
				(type default)
			)
			(layer "F.SilkS")
		)
		(fp_line
			(start -0.7874 0.4064)
			(end -0.7874 -0.4064)
			(stroke
				(width 0.1524)
				(type default)
			)
			(layer "F.SilkS")
		)
		(fp_line
			(start 0.7874 -0.4064)
			(end 0.7874 0.4064)
			(stroke
				(width 0.1524)
				(type default)
			)
			(layer "F.SilkS")
		)
		(fp_line
			(start 0.7874 0.4064)
			(end -0.7874 0.4064)
			(stroke
				(width 0.1524)
				(type default)
			)
			(layer "F.SilkS")
		)
		(fp_line
			(start -0.67945 -0.305054)
			(end -0.12065 -0.305054)
			(stroke
				(width 0.1)
				(type default)
			)
			(layer "F.Fab")
		)
		(fp_line
			(start -0.67945 0.3048)
			(end -0.67945 -0.305054)
			(stroke
				(width 0.1)
				(type default)
			)
			(layer "F.Fab")
		)
		(fp_line
			(start -0.12065 -0.305054)
			(end -0.12065 -0.2794)
			(stroke
				(width 0.1)
				(type default)
			)
			(layer "F.Fab")
		)
		(fp_line
			(start -0.12065 -0.2794)
			(end 0.12065 -0.2794)
			(stroke
				(width 0.1)
				(type default)
			)
			(layer "F.Fab")
		)
		(fp_line
			(start -0.12065 0.2794)
			(end -0.12065 0.3048)
			(stroke
				(width 0.1)
				(type default)
			)
			(layer "F.Fab")
		)
		(fp_line
			(start -0.12065 0.3048)
			(end -0.67945 0.3048)
			(stroke
				(width 0.1)
				(type default)
			)
			(layer "F.Fab")
		)
		(fp_line
			(start 0.120396 0.2794)
			(end -0.12065 0.2794)
			(stroke
				(width 0.1)
				(type default)
			)
			(layer "F.Fab")
		)
		(fp_line
			(start 0.120396 0.3048)
			(end 0.120396 0.2794)
			(stroke
				(width 0.1)
				(type default)
			)
			(layer "F.Fab")
		)
		(fp_line
			(start 0.12065 -0.3048)
			(end 0.67945 -0.3048)
			(stroke
				(width 0.1)
				(type default)
			)
			(layer "F.Fab")
		)
		(fp_line
			(start 0.12065 -0.2794)
			(end 0.12065 -0.3048)
			(stroke
				(width 0.1)
				(type default)
			)
			(layer "F.Fab")
		)
		(fp_line
			(start 0.67945 -0.3048)
			(end 0.67945 0.3048)
			(stroke
				(width 0.1)
				(type default)
			)
			(layer "F.Fab")
		)
		(fp_line
			(start 0.67945 0.3048)
			(end 0.120396 0.3048)
			(stroke
				(width 0.1)
				(type default)
			)
			(layer "F.Fab")
		)
		(pad "1" smd circle
			(at -0.40005 0)
			(size 0 0)
			(layers "F.Cu" "F.Mask" "F.Paste")
			(net "GPU_3V3IO_RSVD4_ISO_R")
		)
		(pad "2" smd circle
			(at 0.40005 0)
			(size 0 0)
			(layers "F.Cu" "F.Mask" "F.Paste")
			(net "GPU_3V3IO_RSVD4_ISO")
		)
	)
	(footprint ""
		(layer "F.Cu")
		(at 303.348898 -15.62481)
		(property "Reference" "R4205"
			(at 0 0 0)
			(layer "F.SilkS")
			(hide yes)
			(effects
				(font
					(size 1.27 1.27)
				)
			)
		)
		(property "Value" ""
			(at 0 0 0)
			(layer "F.Fab")
			(effects
				(font
					(size 1.27 1.27)
				)
			)
		)
		(duplicate_pad_numbers_are_jumpers no)
		(fp_line
			(start -0.7874 -0.4064)
			(end 0.7874 -0.4064)
			(stroke
				(width 0.1524)
				(type default)
			)
			(layer "F.SilkS")
		)
		(fp_line
			(start -0.7874 0.4064)
			(end -0.7874 -0.4064)
			(stroke
				(width 0.1524)
				(type default)
			)
			(layer "F.SilkS")
		)
		(fp_line
			(start 0.7874 -0.4064)
			(end 0.7874 0.4064)
			(stroke
				(width 0.1524)
				(type default)
			)
			(layer "F.SilkS")
		)
		(fp_line
			(start 0.7874 0.4064)
			(end -0.7874 0.4064)
			(stroke
				(width 0.1524)
				(type default)
			)
			(layer "F.SilkS")
		)
		(fp_line
			(start -0.67945 -0.305054)
			(end -0.12065 -0.305054)
			(stroke
				(width 0.1)
				(type default)
			)
			(layer "F.Fab")
		)
		(fp_line
			(start -0.67945 0.3048)
			(end -0.67945 -0.305054)
			(stroke
				(width 0.1)
				(type default)
			)
			(layer "F.Fab")
		)
		(fp_line
			(start -0.12065 -0.305054)
			(end -0.12065 -0.2794)
			(stroke
				(width 0.1)
				(type default)
			)
			(layer "F.Fab")
		)
		(fp_line
			(start -0.12065 -0.2794)
			(end 0.12065 -0.2794)
			(stroke
				(width 0.1)
				(type default)
			)
			(layer "F.Fab")
		)
		(fp_line
			(start -0.12065 0.2794)
			(end -0.12065 0.3048)
			(stroke
				(width 0.1)
				(type default)
			)
			(layer "F.Fab")
		)
		(fp_line
			(start -0.12065 0.3048)
			(end -0.67945 0.3048)
			(stroke
				(width 0.1)
				(type default)
			)
			(layer "F.Fab")
		)
		(fp_line
			(start 0.120396 0.2794)
			(end -0.12065 0.2794)
			(stroke
				(width 0.1)
				(type default)
			)
			(layer "F.Fab")
		)
		(fp_line
			(start 0.120396 0.3048)
			(end 0.120396 0.2794)
			(stroke
				(width 0.1)
				(type default)
			)
			(layer "F.Fab")
		)
		(fp_line
			(start 0.12065 -0.3048)
			(end 0.67945 -0.3048)
			(stroke
				(width 0.1)
				(type default)
			)
			(layer "F.Fab")
		)
		(fp_line
			(start 0.12065 -0.2794)
			(end 0.12065 -0.3048)
			(stroke
				(width 0.1)
				(type default)
			)
			(layer "F.Fab")
		)
		(fp_line
			(start 0.67945 -0.3048)
			(end 0.67945 0.3048)
			(stroke
				(width 0.1)
				(type default)
			)
			(layer "F.Fab")
		)
		(fp_line
			(start 0.67945 0.3048)
			(end 0.120396 0.3048)
			(stroke
				(width 0.1)
				(type default)
			)
			(layer "F.Fab")
		)
		(pad "1" smd circle
			(at -0.40005 0)
			(size 0 0)
			(layers "F.Cu" "F.Mask" "F.Paste")
			(net "U271_1_ADD0")
		)
		(pad "2" smd circle
			(at 0.40005 0)
			(size 0 0)
			(layers "F.Cu" "F.Mask" "F.Paste")
			(net "GND")
		)
	)
)
